(kicad_pcb
	(version 20260206)
	(generator "pcbnew")
	(generator_version "10.0")
	(general
		(thickness 1.6)
		(legacy_teardrops no)
	)
	(paper "A4")
	(title_block
		(title "01162023_DA0F0TEBIF0_F0T_Expander_BD_F_brd_V02_OCP.brd")
		(comment 1 "Grand Teton / footprints 3428-3435 of 9728")
	)
	(layers
		(0 "F.Cu" signal "TOP")
		(4 "In1.Cu" signal "GND")
		(6 "In2.Cu" signal "VCC")
		(8 "In3.Cu" signal "VCC1")
		(10 "In4.Cu" signal "GND1")
		(12 "In5.Cu" signal "IN1")
		(14 "In6.Cu" signal "GND2")
		(16 "In7.Cu" signal "IN2")
		(18 "In8.Cu" signal "GND3")
		(20 "In9.Cu" signal "IN3")
		(22 "In10.Cu" signal "GND4")
		(24 "In11.Cu" signal "IN4")
		(26 "In12.Cu" signal "GND5")
		(28 "In13.Cu" signal "IN5")
		(30 "In14.Cu" signal "GND6")
		(32 "In15.Cu" signal "IN6")
		(34 "In16.Cu" signal "GND7")
		(2 "B.Cu" signal "BOTTOM")
		(9 "F.Adhes" user "F.Adhesive")
		(11 "B.Adhes" user "B.Adhesive")
		(13 "F.Paste" user "Package Geometry/Pastemask Top")
		(15 "B.Paste" user "Package Geometry/Pastemask Bottom")
		(5 "F.SilkS" user "Ref Des/Silkscreen Top")
		(7 "B.SilkS" user "Ref Des/Silkscreen Bottom")
		(1 "F.Mask" user "Board Geometry/Soldermask Top")
		(3 "B.Mask" user "Board Geometry/Soldermask Bottom")
		(17 "Dwgs.User" user "User.Drawings")
		(19 "Cmts.User" user "User.Comments")
		(21 "Eco1.User" user "User.Eco1")
		(23 "Eco2.User" user "User.Eco2")
		(25 "Edge.Cuts" user "Board Geometry/Outline")
		(27 "Margin" user)
		(31 "F.CrtYd" user "Package Geometry/Place Bound Top")
		(29 "B.CrtYd" user "Package Geometry/Place Bound Bottom")
		(35 "F.Fab" user "Ref Des/Assembly Top")
		(33 "B.Fab" user "Ref Des/Assembly Bottom")
	)
	(footprint ""
		(layer "F.Cu")
		(at 244.809264 -119.105426 -90)
		(property "Reference" "R6038"
			(at 0 0 270)
			(layer "F.SilkS")
			(hide yes)
			(effects
				(font
					(size 1.27 1.27)
				)
			)
		)
		(property "Value" ""
			(at 0 0 270)
			(layer "F.Fab")
			(effects
				(font
					(size 1.27 1.27)
				)
			)
		)
		(duplicate_pad_numbers_are_jumpers no)
		(fp_line
			(start -0.7874 0.4064)
			(end -0.7874 -0.4064)
			(stroke
				(width 0.1524)
				(type default)
			)
			(layer "F.SilkS")
		)
		(fp_line
			(start 0.7874 0.4064)
			(end -0.7874 0.4064)
			(stroke
				(width 0.1524)
				(type default)
			)
			(layer "F.SilkS")
		)
		(fp_line
			(start -0.7874 -0.4064)
			(end 0.7874 -0.4064)
			(stroke
				(width 0.1524)
				(type default)
			)
			(layer "F.SilkS")
		)
		(fp_line
			(start 0.7874 -0.4064)
			(end 0.7874 0.4064)
			(stroke
				(width 0.1524)
				(type default)
			)
			(layer "F.SilkS")
		)
		(fp_line
			(start -0.67945 0.3048)
			(end -0.67945 -0.305054)
			(stroke
				(width 0.1)
				(type default)
			)
			(layer "F.Fab")
		)
		(fp_line
			(start -0.12065 0.3048)
			(end -0.67945 0.3048)
			(stroke
				(width 0.1)
				(type default)
			)
			(layer "F.Fab")
		)
		(fp_line
			(start 0.120396 0.3048)
			(end 0.120396 0.2794)
			(stroke
				(width 0.1)
				(type default)
			)
			(layer "F.Fab")
		)
		(fp_line
			(start 0.67945 0.3048)
			(end 0.120396 0.3048)
			(stroke
				(width 0.1)
				(type default)
			)
			(layer "F.Fab")
		)
		(fp_line
			(start -0.12065 0.2794)
			(end -0.12065 0.3048)
			(stroke
				(width 0.1)
				(type default)
			)
			(layer "F.Fab")
		)
		(fp_line
			(start 0.120396 0.2794)
			(end -0.12065 0.2794)
			(stroke
				(width 0.1)
				(type default)
			)
			(layer "F.Fab")
		)
		(fp_line
			(start -0.12065 -0.2794)
			(end 0.12065 -0.2794)
			(stroke
				(width 0.1)
				(type default)
			)
			(layer "F.Fab")
		)
		(fp_line
			(start 0.12065 -0.2794)
			(end 0.12065 -0.3048)
			(stroke
				(width 0.1)
				(type default)
			)
			(layer "F.Fab")
		)
		(fp_line
			(start 0.12065 -0.3048)
			(end 0.67945 -0.3048)
			(stroke
				(width 0.1)
				(type default)
			)
			(layer "F.Fab")
		)
		(fp_line
			(start 0.67945 -0.3048)
			(end 0.67945 0.3048)
			(stroke
				(width 0.1)
				(type default)
			)
			(layer "F.Fab")
		)
		(fp_line
			(start -0.67945 -0.305054)
			(end -0.12065 -0.305054)
			(stroke
				(width 0.1)
				(type default)
			)
			(layer "F.Fab")
		)
		(fp_line
			(start -0.12065 -0.305054)
			(end -0.12065 -0.2794)
			(stroke
				(width 0.1)
				(type default)
			)
			(layer "F.Fab")
		)
		(pad "1" smd circle
			(at -0.40005 0 270)
			(size 0 0)
			(layers "F.Cu" "F.Mask" "F.Paste")
			(net "P3V3_NIC4")
		)
		(pad "2" smd circle
			(at 0.40005 0 270)
			(size 0 0)
			(layers "F.Cu" "F.Mask" "F.Paste")
			(net "P3V3_NIC4_PG_G1")
		)
	)
	(footprint ""
		(layer "F.Cu")
		(at 151.50719 -379.389132 180)
		(property "Reference" "C4096"
			(at 0 0 180)
			(layer "F.SilkS")
			(hide yes)
			(effects
				(font
					(size 1.27 1.27)
				)
			)
		)
		(property "Value" ""
			(at 0 0 180)
			(layer "F.Fab")
			(effects
				(font
					(size 1.27 1.27)
				)
			)
		)
		(duplicate_pad_numbers_are_jumpers no)
		(fp_line
			(start 0.7874 0.4064)
			(end -0.7874 0.4064)
			(stroke
				(width 0.1524)
				(type default)
			)
			(layer "F.SilkS")
		)
		(fp_line
			(start 0.7874 -0.4064)
			(end 0.7874 0.4064)
			(stroke
				(width 0.1524)
				(type default)
			)
			(layer "F.SilkS")
		)
		(fp_line
			(start -0.7874 0.4064)
			(end -0.7874 -0.4064)
			(stroke
				(width 0.1524)
				(type default)
			)
			(layer "F.SilkS")
		)
		(fp_line
			(start -0.7874 -0.4064)
			(end 0.7874 -0.4064)
			(stroke
				(width 0.1524)
				(type default)
			)
			(layer "F.SilkS")
		)
		(fp_line
			(start 0.67945 0.3048)
			(end 0.120396 0.3048)
			(stroke
				(width 0.1)
				(type default)
			)
			(layer "F.Fab")
		)
		(fp_line
			(start 0.67945 -0.3048)
			(end 0.67945 0.3048)
			(stroke
				(width 0.1)
				(type default)
			)
			(layer "F.Fab")
		)
		(fp_line
			(start 0.12065 -0.2794)
			(end 0.12065 -0.3048)
			(stroke
				(width 0.1)
				(type default)
			)
			(layer "F.Fab")
		)
		(fp_line
			(start 0.12065 -0.3048)
			(end 0.67945 -0.3048)
			(stroke
				(width 0.1)
				(type default)
			)
			(layer "F.Fab")
		)
		(fp_line
			(start 0.120396 0.3048)
			(end 0.120396 0.2794)
			(stroke
				(width 0.1)
				(type default)
			)
			(layer "F.Fab")
		)
		(fp_line
			(start 0.120396 0.2794)
			(end -0.12065 0.2794)
			(stroke
				(width 0.1)
				(type default)
			)
			(layer "F.Fab")
		)
		(fp_line
			(start -0.12065 0.3048)
			(end -0.67945 0.3048)
			(stroke
				(width 0.1)
				(type default)
			)
			(layer "F.Fab")
		)
		(fp_line
			(start -0.12065 0.2794)
			(end -0.12065 0.3048)
			(stroke
				(width 0.1)
				(type default)
			)
			(layer "F.Fab")
		)
		(fp_line
			(start -0.12065 -0.2794)
			(end 0.12065 -0.2794)
			(stroke
				(width 0.1)
				(type default)
			)
			(layer "F.Fab")
		)
		(fp_line
			(start -0.12065 -0.305054)
			(end -0.12065 -0.2794)
			(stroke
				(width 0.1)
				(type default)
			)
			(layer "F.Fab")
		)
		(fp_line
			(start -0.67945 0.3048)
			(end -0.67945 -0.305054)
			(stroke
				(width 0.1)
				(type default)
			)
			(layer "F.Fab")
		)
		(fp_line
			(start -0.67945 -0.305054)
			(end -0.12065 -0.305054)
			(stroke
				(width 0.1)
				(type default)
			)
			(layer "F.Fab")
		)
		(pad "1" smd circle
			(at -0.40005 0 180)
			(size 0 0)
			(layers "F.Cu" "F.Mask" "F.Paste")
			(net "GND")
		)
		(pad "2" smd circle
			(at 0.40005 0 180)
			(size 0 0)
			(layers "F.Cu" "F.Mask" "F.Paste")
			(net "GPU_FPGA_EROT_FATALERR_N")
		)
	)
	(footprint ""
		(layer "F.Cu")
		(at 328.03973 -70.52437 90)
		(property "Reference" "PC876"
			(at 0 0 90)
			(layer "F.SilkS")
			(hide yes)
			(effects
				(font
					(size 1.27 1.27)
				)
			)
		)
		(property "Value" ""
			(at 0 0 90)
			(layer "F.Fab")
			(effects
				(font
					(size 1.27 1.27)
				)
			)
		)
		(duplicate_pad_numbers_are_jumpers no)
		(fp_line
			(start 1.524 -0.762)
			(end 1.524 0.762)
			(stroke
				(width 0.1524)
				(type default)
			)
			(layer "F.SilkS")
		)
		(fp_line
			(start -1.524 -0.762)
			(end 1.524 -0.762)
			(stroke
				(width 0.1524)
				(type default)
			)
			(layer "F.SilkS")
		)
		(fp_line
			(start 1.524 0.762)
			(end -1.524 0.762)
			(stroke
				(width 0.1524)
				(type default)
			)
			(layer "F.SilkS")
		)
		(fp_line
			(start -1.524 0.762)
			(end -1.524 -0.762)
			(stroke
				(width 0.1524)
				(type default)
			)
			(layer "F.SilkS")
		)
		(fp_line
			(start 1.1049 -0.724916)
			(end -1.1049 -0.724916)
			(stroke
				(width 0.1)
				(type default)
			)
			(layer "F.Fab")
		)
		(fp_line
			(start -1.1049 -0.724916)
			(end -1.1049 0.724916)
			(stroke
				(width 0.1)
				(type default)
			)
			(layer "F.Fab")
		)
		(fp_line
			(start 1.1049 0.724916)
			(end 1.1049 -0.724916)
			(stroke
				(width 0.1)
				(type default)
			)
			(layer "F.Fab")
		)
		(fp_line
			(start -1.1049 0.724916)
			(end 1.1049 0.724916)
			(stroke
				(width 0.1)
				(type default)
			)
			(layer "F.Fab")
		)
		(pad "1" smd rect
			(at -0.889 0 270)
			(size 1.016 1.27)
			(layers "F.Cu" "F.Mask" "F.Paste")
			(net "P12V_SSD11_R")
		)
		(pad "2" smd rect
			(at 0.889 0 270)
			(size 1.016 1.27)
			(layers "F.Cu" "F.Mask" "F.Paste")
			(net "GND")
		)
	)
	(footprint ""
		(layer "F.Cu")
		(at 358.792272 -251.054362)
		(property "Reference" "R1776"
			(at 0 0 0)
			(layer "F.SilkS")
			(hide yes)
			(effects
				(font
					(size 1.27 1.27)
				)
			)
		)
		(property "Value" ""
			(at 0 0 0)
			(layer "F.Fab")
			(effects
				(font
					(size 1.27 1.27)
				)
			)
		)
		(duplicate_pad_numbers_are_jumpers no)
		(fp_line
			(start -0.7874 -0.4064)
			(end 0.7874 -0.4064)
			(stroke
				(width 0.1524)
				(type default)
			)
			(layer "F.SilkS")
		)
		(fp_line
			(start -0.7874 0.4064)
			(end -0.7874 -0.4064)
			(stroke
				(width 0.1524)
				(type default)
			)
			(layer "F.SilkS")
		)
		(fp_line
			(start 0.7874 -0.4064)
			(end 0.7874 0.4064)
			(stroke
				(width 0.1524)
				(type default)
			)
			(layer "F.SilkS")
		)
		(fp_line
			(start 0.7874 0.4064)
			(end -0.7874 0.4064)
			(stroke
				(width 0.1524)
				(type default)
			)
			(layer "F.SilkS")
		)
		(fp_line
			(start -0.67945 -0.305054)
			(end -0.12065 -0.305054)
			(stroke
				(width 0.1)
				(type default)
			)
			(layer "F.Fab")
		)
		(fp_line
			(start -0.67945 0.3048)
			(end -0.67945 -0.305054)
			(stroke
				(width 0.1)
				(type default)
			)
			(layer "F.Fab")
		)
		(fp_line
			(start -0.12065 -0.305054)
			(end -0.12065 -0.2794)
			(stroke
				(width 0.1)
				(type default)
			)
			(layer "F.Fab")
		)
		(fp_line
			(start -0.12065 -0.2794)
			(end 0.12065 -0.2794)
			(stroke
				(width 0.1)
				(type default)
			)
			(layer "F.Fab")
		)
		(fp_line
			(start -0.12065 0.2794)
			(end -0.12065 0.3048)
			(stroke
				(width 0.1)
				(type default)
			)
			(layer "F.Fab")
		)
		(fp_line
			(start -0.12065 0.3048)
			(end -0.67945 0.3048)
			(stroke
				(width 0.1)
				(type default)
			)
			(layer "F.Fab")
		)
		(fp_line
			(start 0.120396 0.2794)
			(end -0.12065 0.2794)
			(stroke
				(width 0.1)
				(type default)
			)
			(layer "F.Fab")
		)
		(fp_line
			(start 0.120396 0.3048)
			(end 0.120396 0.2794)
			(stroke
				(width 0.1)
				(type default)
			)
			(layer "F.Fab")
		)
		(fp_line
			(start 0.12065 -0.3048)
			(end 0.67945 -0.3048)
			(stroke
				(width 0.1)
				(type default)
			)
			(layer "F.Fab")
		)
		(fp_line
			(start 0.12065 -0.2794)
			(end 0.12065 -0.3048)
			(stroke
				(width 0.1)
				(type default)
			)
			(layer "F.Fab")
		)
		(fp_line
			(start 0.67945 -0.3048)
			(end 0.67945 0.3048)
			(stroke
				(width 0.1)
				(type default)
			)
			(layer "F.Fab")
		)
		(fp_line
			(start 0.67945 0.3048)
			(end 0.120396 0.3048)
			(stroke
				(width 0.1)
				(type default)
			)
			(layer "F.Fab")
		)
		(pad "1" smd circle
			(at -0.40005 0)
			(size 0 0)
			(layers "F.Cu" "F.Mask" "F.Paste")
			(net "SMB_BIC_I2C6_MUX_VR_R_SCL")
		)
		(pad "2" smd circle
			(at 0.40005 0)
			(size 0 0)
			(layers "F.Cu" "F.Mask" "F.Paste")
			(net "SMB_BIC_I2C6_MUX_VR_SCL")
		)
	)
	(footprint ""
		(layer "F.Cu")
		(at 336.042 -165.989)
		(property "Reference" "R4727"
			(at 0 0 0)
			(layer "F.SilkS")
			(hide yes)
			(effects
				(font
					(size 1.27 1.27)
				)
			)
		)
		(property "Value" ""
			(at 0 0 0)
			(layer "F.Fab")
			(effects
				(font
					(size 1.27 1.27)
				)
			)
		)
		(duplicate_pad_numbers_are_jumpers no)
		(fp_line
			(start -0.7874 -0.4064)
			(end 0.7874 -0.4064)
			(stroke
				(width 0.1524)
				(type default)
			)
			(layer "F.SilkS")
		)
		(fp_line
			(start -0.7874 0.4064)
			(end -0.7874 -0.4064)
			(stroke
				(width 0.1524)
				(type default)
			)
			(layer "F.SilkS")
		)
		(fp_line
			(start 0.7874 -0.4064)
			(end 0.7874 0.4064)
			(stroke
				(width 0.1524)
				(type default)
			)
			(layer "F.SilkS")
		)
		(fp_line
			(start 0.7874 0.4064)
			(end -0.7874 0.4064)
			(stroke
				(width 0.1524)
				(type default)
			)
			(layer "F.SilkS")
		)
		(fp_line
			(start -0.67945 -0.305054)
			(end -0.12065 -0.305054)
			(stroke
				(width 0.1)
				(type default)
			)
			(layer "F.Fab")
		)
		(fp_line
			(start -0.67945 0.3048)
			(end -0.67945 -0.305054)
			(stroke
				(width 0.1)
				(type default)
			)
			(layer "F.Fab")
		)
		(fp_line
			(start -0.12065 -0.305054)
			(end -0.12065 -0.2794)
			(stroke
				(width 0.1)
				(type default)
			)
			(layer "F.Fab")
		)
		(fp_line
			(start -0.12065 -0.2794)
			(end 0.12065 -0.2794)
			(stroke
				(width 0.1)
				(type default)
			)
			(layer "F.Fab")
		)
		(fp_line
			(start -0.12065 0.2794)
			(end -0.12065 0.3048)
			(stroke
				(width 0.1)
				(type default)
			)
			(layer "F.Fab")
		)
		(fp_line
			(start -0.12065 0.3048)
			(end -0.67945 0.3048)
			(stroke
				(width 0.1)
				(type default)
			)
			(layer "F.Fab")
		)
		(fp_line
			(start 0.120396 0.2794)
			(end -0.12065 0.2794)
			(stroke
				(width 0.1)
				(type default)
			)
			(layer "F.Fab")
		)
		(fp_line
			(start 0.120396 0.3048)
			(end 0.120396 0.2794)
			(stroke
				(width 0.1)
				(type default)
			)
			(layer "F.Fab")
		)
		(fp_line
			(start 0.12065 -0.3048)
			(end 0.67945 -0.3048)
			(stroke
				(width 0.1)
				(type default)
			)
			(layer "F.Fab")
		)
		(fp_line
			(start 0.12065 -0.2794)
			(end 0.12065 -0.3048)
			(stroke
				(width 0.1)
				(type default)
			)
			(layer "F.Fab")
		)
		(fp_line
			(start 0.67945 -0.3048)
			(end 0.67945 0.3048)
			(stroke
				(width 0.1)
				(type default)
			)
			(layer "F.Fab")
		)
		(fp_line
			(start 0.67945 0.3048)
			(end 0.120396 0.3048)
			(stroke
				(width 0.1)
				(type default)
			)
			(layer "F.Fab")
		)
		(pad "1" smd circle
			(at -0.40005 0)
			(size 0 0)
			(layers "F.Cu" "F.Mask" "F.Paste")
			(net "P3V3_AUX")
		)
		(pad "2" smd circle
			(at 0.40005 0)
			(size 0 0)
			(layers "F.Cu" "F.Mask" "F.Paste")
			(net "SSD11_PEX_PWR_EN_R")
		)
	)
	(footprint ""
		(layer "F.Cu")
		(at 171.979844 -138.6332 180)
		(property "Reference" "R143"
			(at 0 0 180)
			(layer "F.SilkS")
			(hide yes)
			(effects
				(font
					(size 1.27 1.27)
				)
			)
		)
		(property "Value" ""
			(at 0 0 180)
			(layer "F.Fab")
			(effects
				(font
					(size 1.27 1.27)
				)
			)
		)
		(duplicate_pad_numbers_are_jumpers no)
		(fp_line
			(start 0.7874 0.4064)
			(end -0.7874 0.4064)
			(stroke
				(width 0.1524)
				(type default)
			)
			(layer "F.SilkS")
		)
		(fp_line
			(start 0.7874 -0.4064)
			(end 0.7874 0.4064)
			(stroke
				(width 0.1524)
				(type default)
			)
			(layer "F.SilkS")
		)
		(fp_line
			(start -0.7874 0.4064)
			(end -0.7874 -0.4064)
			(stroke
				(width 0.1524)
				(type default)
			)
			(layer "F.SilkS")
		)
		(fp_line
			(start -0.7874 -0.4064)
			(end 0.7874 -0.4064)
			(stroke
				(width 0.1524)
				(type default)
			)
			(layer "F.SilkS")
		)
		(fp_line
			(start 0.67945 0.3048)
			(end 0.120396 0.3048)
			(stroke
				(width 0.1)
				(type default)
			)
			(layer "F.Fab")
		)
		(fp_line
			(start 0.67945 -0.3048)
			(end 0.67945 0.3048)
			(stroke
				(width 0.1)
				(type default)
			)
			(layer "F.Fab")
		)
		(fp_line
			(start 0.12065 -0.2794)
			(end 0.12065 -0.3048)
			(stroke
				(width 0.1)
				(type default)
			)
			(layer "F.Fab")
		)
		(fp_line
			(start 0.12065 -0.3048)
			(end 0.67945 -0.3048)
			(stroke
				(width 0.1)
				(type default)
			)
			(layer "F.Fab")
		)
		(fp_line
			(start 0.120396 0.3048)
			(end 0.120396 0.2794)
			(stroke
				(width 0.1)
				(type default)
			)
			(layer "F.Fab")
		)
		(fp_line
			(start 0.120396 0.2794)
			(end -0.12065 0.2794)
			(stroke
				(width 0.1)
				(type default)
			)
			(layer "F.Fab")
		)
		(fp_line
			(start -0.12065 0.3048)
			(end -0.67945 0.3048)
			(stroke
				(width 0.1)
				(type default)
			)
			(layer "F.Fab")
		)
		(fp_line
			(start -0.12065 0.2794)
			(end -0.12065 0.3048)
			(stroke
				(width 0.1)
				(type default)
			)
			(layer "F.Fab")
		)
		(fp_line
			(start -0.12065 -0.2794)
			(end 0.12065 -0.2794)
			(stroke
				(width 0.1)
				(type default)
			)
			(layer "F.Fab")
		)
		(fp_line
			(start -0.12065 -0.305054)
			(end -0.12065 -0.2794)
			(stroke
				(width 0.1)
				(type default)
			)
			(layer "F.Fab")
		)
		(fp_line
			(start -0.67945 0.3048)
			(end -0.67945 -0.305054)
			(stroke
				(width 0.1)
				(type default)
			)
			(layer "F.Fab")
		)
		(fp_line
			(start -0.67945 -0.305054)
			(end -0.12065 -0.305054)
			(stroke
				(width 0.1)
				(type default)
			)
			(layer "F.Fab")
		)
		(pad "1" smd circle
			(at -0.40005 0 180)
			(size 0 0)
			(layers "F.Cu" "F.Mask" "F.Paste")
			(net "PRSNT_NIC2_N")
		)
		(pad "2" smd circle
			(at 0.40005 0 180)
			(size 0 0)
			(layers "F.Cu" "F.Mask" "F.Paste")
			(net "PRSNTB2_NIC2_N")
		)
	)
	(footprint ""
		(layer "F.Cu")
		(at 295.852342 -343.952322 90)
		(property "Reference" "C587"
			(at 0 0 90)
			(layer "F.SilkS")
			(hide yes)
			(effects
				(font
					(size 1.27 1.27)
				)
			)
		)
		(property "Value" ""
			(at 0 0 90)
			(layer "F.Fab")
			(effects
				(font
					(size 1.27 1.27)
				)
			)
		)
		(duplicate_pad_numbers_are_jumpers no)
		(fp_line
			(start 0.299974 -0.150114)
			(end 0.299974 0.150114)
			(stroke
				(width 0.1)
				(type default)
			)
			(layer "F.Fab")
		)
		(fp_line
			(start -0.299974 -0.150114)
			(end 0.299974 -0.150114)
			(stroke
				(width 0.1)
				(type default)
			)
			(layer "F.Fab")
		)
		(fp_line
			(start 0.299974 0.150114)
			(end -0.299974 0.150114)
			(stroke
				(width 0.1)
				(type default)
			)
			(layer "F.Fab")
		)
		(fp_line
			(start -0.299974 0.150114)
			(end -0.299974 -0.150114)
			(stroke
				(width 0.1)
				(type default)
			)
			(layer "F.Fab")
		)
		(pad "1" smd rect
			(at -0.2667 0 90)
			(size 0.3048 0.381)
			(layers "F.Cu" "F.Mask" "F.Paste")
			(net "P5E_PEX2_STN7_TX_DP<125>")
		)
		(pad "2" smd rect
			(at 0.2667 0 90)
			(size 0.3048 0.381)
			(layers "F.Cu" "F.Mask" "F.Paste")
			(net "P5E_PEX2_STN7_TX_C_DP<125>")
		)
	)
	(footprint ""
		(layer "F.Cu")
		(at 166.184072 -356.244906 90)
		(property "Reference" "C2517"
			(at 0 0 90)
			(layer "F.SilkS")
			(hide yes)
			(effects
				(font
					(size 1.27 1.27)
				)
			)
		)
		(property "Value" ""
			(at 0 0 90)
			(layer "F.Fab")
			(effects
				(font
					(size 1.27 1.27)
				)
			)
		)
		(duplicate_pad_numbers_are_jumpers no)
		(fp_line
			(start 0.299974 -0.150114)
			(end 0.299974 0.150114)
			(stroke
				(width 0.1)
				(type default)
			)
			(layer "F.Fab")
		)
		(fp_line
			(start -0.299974 -0.150114)
			(end 0.299974 -0.150114)
			(stroke
				(width 0.1)
				(type default)
			)
			(layer "F.Fab")
		)
		(fp_line
			(start 0.299974 0.150114)
			(end -0.299974 0.150114)
			(stroke
				(width 0.1)
				(type default)
			)
			(layer "F.Fab")
		)
		(fp_line
			(start -0.299974 0.150114)
			(end -0.299974 -0.150114)
			(stroke
				(width 0.1)
				(type default)
			)
			(layer "F.Fab")
		)
		(pad "1" smd rect
			(at -0.2667 0 90)
			(size 0.3048 0.381)
			(layers "F.Cu" "F.Mask" "F.Paste")
			(net "P5E_PEX1_STN4_TX_DN<77>")
		)
		(pad "2" smd rect
			(at 0.2667 0 90)
			(size 0.3048 0.381)
			(layers "F.Cu" "F.Mask" "F.Paste")
			(net "P5E_PEX1_STN4_TX_C_DN<77>")
		)
	)
)
